# T6G (Grand Teton) — schematic netlist excerpt (pin names and nets, part order shuffled) for the footprints in the layout excerpt that follows; sources: Cadence DE-HDL packaged netlist, KiCad conversion of 04192023_DAF0TMB3IC0_F0TG_MB_C_brd_V02_OCP.brd

C812  Q_CAP_DIFFBUS  DIFF BUS_0.22UF 6.3V 20% X6S  pkg C0201  page 65 : \1\ = P5E_CPU1_P0_TX_C_DN<12> ; \2\ = P5E_CPU1_P0_TX_DN<12>
C1339  Q_CAP  0.1UF 25V 10% X7R  pkg 0402  page 159 : A = P3V3_AUX ; B = GND
R4553  Q_RES  4.7K 5% CHIP  pkg 0402LF  page 241 : A = P3V3_AUX ; B = HPDB_HSC_PWRGD_N

(kicad_pcb
	(version 20260206)
	(generator "pcbnew")
	(generator_version "10.0")
	(general
		(thickness 1.6)
		(legacy_teardrops no)
	)
	(paper "A4")
	(title_block
		(title "04192023_DAF0TMB3IC0_F0TG_MB_C_brd_V02_OCP.brd")
		(comment 1 "Grand Teton / footprints 1374-1376 of 8354")
	)
	(layers
		(0 "F.Cu" signal "TOP")
		(4 "In1.Cu" signal "GND")
		(6 "In2.Cu" signal "IN1")
		(8 "In3.Cu" signal "GND1")
		(10 "In4.Cu" signal "IN2")
		(12 "In5.Cu" signal "GND2")
		(14 "In6.Cu" signal "IN3")
		(16 "In7.Cu" signal "GND3")
		(18 "In8.Cu" signal "VCC")
		(20 "In9.Cu" signal "VCC1")
		(22 "In10.Cu" signal "GND4")
		(24 "In11.Cu" signal "IN4")
		(26 "In12.Cu" signal "GND5")
		(28 "In13.Cu" signal "IN5")
		(30 "In14.Cu" signal "GND6")
		(32 "In15.Cu" signal "IN6")
		(34 "In16.Cu" signal "GND7")
		(2 "B.Cu" signal "BOTTOM")
		(9 "F.Adhes" user "F.Adhesive")
		(11 "B.Adhes" user "B.Adhesive")
		(13 "F.Paste" user "Package Geometry/Pastemask Top")
		(15 "B.Paste" user "Package Geometry/Pastemask Bottom")
		(5 "F.SilkS" user "Ref Des/Silkscreen Top")
		(7 "B.SilkS" user "Ref Des/Silkscreen Bottom")
		(1 "F.Mask" user "Board Geometry/Soldermask Top")
		(3 "B.Mask" user "Board Geometry/Soldermask Bottom")
		(17 "Dwgs.User" user "User.Drawings")
		(19 "Cmts.User" user "User.Comments")
		(21 "Eco1.User" user "User.Eco1")
		(23 "Eco2.User" user "User.Eco2")
		(25 "Edge.Cuts" user "Board Geometry/Outline")
		(27 "Margin" user)
		(31 "F.CrtYd" user "Package Geometry/Place Bound Top")
		(29 "B.CrtYd" user "Package Geometry/Place Bound Bottom")
		(35 "F.Fab" user "Ref Des/Assembly Top")
		(33 "B.Fab" user "Ref Des/Assembly Bottom")
	)
	(footprint ""
		(layer "F.Cu")
		(at 284.317694 -436.304436 90)
		(property "Reference" "R4553"
			(at 0 0 90)
			(layer "F.SilkS")
			(hide yes)
			(effects
				(font
					(size 1.27 1.27)
				)
			)
		)
		(property "Value" ""
			(at 0 0 90)
			(layer "F.Fab")
			(effects
				(font
					(size 1.27 1.27)
				)
			)
		)
		(duplicate_pad_numbers_are_jumpers no)
		(fp_line
			(start 0.7874 -0.4064)
			(end 0.7874 0.4064)
			(stroke
				(width 0.1524)
				(type default)
			)
			(layer "F.SilkS")
		)
		(fp_line
			(start -0.7874 -0.4064)
			(end 0.7874 -0.4064)
			(stroke
				(width 0.1524)
				(type default)
			)
			(layer "F.SilkS")
		)
		(fp_line
			(start 0.7874 0.4064)
			(end -0.7874 0.4064)
			(stroke
				(width 0.1524)
				(type default)
			)
			(layer "F.SilkS")
		)
		(fp_line
			(start -0.7874 0.4064)
			(end -0.7874 -0.4064)
			(stroke
				(width 0.1524)
				(type default)
			)
			(layer "F.SilkS")
		)
		(fp_line
			(start -0.12065 -0.305054)
			(end -0.12065 -0.2794)
			(stroke
				(width 0.1)
				(type default)
			)
			(layer "F.Fab")
		)
		(fp_line
			(start -0.67945 -0.305054)
			(end -0.12065 -0.305054)
			(stroke
				(width 0.1)
				(type default)
			)
			(layer "F.Fab")
		)
		(fp_line
			(start 0.67945 -0.3048)
			(end 0.67945 0.3048)
			(stroke
				(width 0.1)
				(type default)
			)
			(layer "F.Fab")
		)
		(fp_line
			(start 0.12065 -0.3048)
			(end 0.67945 -0.3048)
			(stroke
				(width 0.1)
				(type default)
			)
			(layer "F.Fab")
		)
		(fp_line
			(start 0.12065 -0.2794)
			(end 0.12065 -0.3048)
			(stroke
				(width 0.1)
				(type default)
			)
			(layer "F.Fab")
		)
		(fp_line
			(start -0.12065 -0.2794)
			(end 0.12065 -0.2794)
			(stroke
				(width 0.1)
				(type default)
			)
			(layer "F.Fab")
		)
		(fp_line
			(start 0.120396 0.2794)
			(end -0.12065 0.2794)
			(stroke
				(width 0.1)
				(type default)
			)
			(layer "F.Fab")
		)
		(fp_line
			(start -0.12065 0.2794)
			(end -0.12065 0.3048)
			(stroke
				(width 0.1)
				(type default)
			)
			(layer "F.Fab")
		)
		(fp_line
			(start 0.67945 0.3048)
			(end 0.120396 0.3048)
			(stroke
				(width 0.1)
				(type default)
			)
			(layer "F.Fab")
		)
		(fp_line
			(start 0.120396 0.3048)
			(end 0.120396 0.2794)
			(stroke
				(width 0.1)
				(type default)
			)
			(layer "F.Fab")
		)
		(fp_line
			(start -0.12065 0.3048)
			(end -0.67945 0.3048)
			(stroke
				(width 0.1)
				(type default)
			)
			(layer "F.Fab")
		)
		(fp_line
			(start -0.67945 0.3048)
			(end -0.67945 -0.305054)
			(stroke
				(width 0.1)
				(type default)
			)
			(layer "F.Fab")
		)
		(pad "1" smd circle
			(at -0.40005 0 90)
			(size 0 0)
			(layers "F.Cu" "F.Mask" "F.Paste")
			(net "P3V3_AUX")
		)
		(pad "2" smd circle
			(at 0.40005 0 90)
			(size 0 0)
			(layers "F.Cu" "F.Mask" "F.Paste")
			(net "HPDB_HSC_PWRGD_N")
		)
	)
	(footprint ""
		(layer "F.Cu")
		(at 180.772308 -165.292024 90)
		(property "Reference" "C1339"
			(at 0 0 90)
			(layer "F.SilkS")
			(hide yes)
			(effects
				(font
					(size 1.27 1.27)
				)
			)
		)
		(property "Value" ""
			(at 0 0 90)
			(layer "F.Fab")
			(effects
				(font
					(size 1.27 1.27)
				)
			)
		)
		(duplicate_pad_numbers_are_jumpers no)
		(fp_line
			(start 0.7874 -0.4064)
			(end 0.7874 0.4064)
			(stroke
				(width 0.1524)
				(type default)
			)
			(layer "F.SilkS")
		)
		(fp_line
			(start -0.7874 -0.4064)
			(end 0.7874 -0.4064)
			(stroke
				(width 0.1524)
				(type default)
			)
			(layer "F.SilkS")
		)
		(fp_line
			(start 0.7874 0.4064)
			(end -0.7874 0.4064)
			(stroke
				(width 0.1524)
				(type default)
			)
			(layer "F.SilkS")
		)
		(fp_line
			(start -0.7874 0.4064)
			(end -0.7874 -0.4064)
			(stroke
				(width 0.1524)
				(type default)
			)
			(layer "F.SilkS")
		)
		(fp_line
			(start -0.12065 -0.305054)
			(end -0.12065 -0.2794)
			(stroke
				(width 0.1)
				(type default)
			)
			(layer "F.Fab")
		)
		(fp_line
			(start -0.67945 -0.305054)
			(end -0.12065 -0.305054)
			(stroke
				(width 0.1)
				(type default)
			)
			(layer "F.Fab")
		)
		(fp_line
			(start 0.67945 -0.3048)
			(end 0.67945 0.3048)
			(stroke
				(width 0.1)
				(type default)
			)
			(layer "F.Fab")
		)
		(fp_line
			(start 0.12065 -0.3048)
			(end 0.67945 -0.3048)
			(stroke
				(width 0.1)
				(type default)
			)
			(layer "F.Fab")
		)
		(fp_line
			(start 0.12065 -0.2794)
			(end 0.12065 -0.3048)
			(stroke
				(width 0.1)
				(type default)
			)
			(layer "F.Fab")
		)
		(fp_line
			(start -0.12065 -0.2794)
			(end 0.12065 -0.2794)
			(stroke
				(width 0.1)
				(type default)
			)
			(layer "F.Fab")
		)
		(fp_line
			(start 0.120396 0.2794)
			(end -0.12065 0.2794)
			(stroke
				(width 0.1)
				(type default)
			)
			(layer "F.Fab")
		)
		(fp_line
			(start -0.12065 0.2794)
			(end -0.12065 0.3048)
			(stroke
				(width 0.1)
				(type default)
			)
			(layer "F.Fab")
		)
		(fp_line
			(start 0.67945 0.3048)
			(end 0.120396 0.3048)
			(stroke
				(width 0.1)
				(type default)
			)
			(layer "F.Fab")
		)
		(fp_line
			(start 0.120396 0.3048)
			(end 0.120396 0.2794)
			(stroke
				(width 0.1)
				(type default)
			)
			(layer "F.Fab")
		)
		(fp_line
			(start -0.12065 0.3048)
			(end -0.67945 0.3048)
			(stroke
				(width 0.1)
				(type default)
			)
			(layer "F.Fab")
		)
		(fp_line
			(start -0.67945 0.3048)
			(end -0.67945 -0.305054)
			(stroke
				(width 0.1)
				(type default)
			)
			(layer "F.Fab")
		)
		(pad "1" smd circle
			(at -0.40005 0 90)
			(size 0 0)
			(layers "F.Cu" "F.Mask" "F.Paste")
			(net "P3V3_AUX")
		)
		(pad "2" smd circle
			(at 0.40005 0 90)
			(size 0 0)
			(layers "F.Cu" "F.Mask" "F.Paste")
			(net "GND")
		)
	)
	(footprint ""
		(layer "F.Cu")
		(at 66.027554 -370.57203 -90)
		(property "Reference" "C812"
			(at 0 0 270)
			(layer "F.SilkS")
			(hide yes)
			(effects
				(font
					(size 1.27 1.27)
				)
			)
		)
		(property "Value" ""
			(at 0 0 270)
			(layer "F.Fab")
			(effects
				(font
					(size 1.27 1.27)
				)
			)
		)
		(duplicate_pad_numbers_are_jumpers no)
		(fp_line
			(start -0.299974 0.150114)
			(end -0.299974 -0.150114)
			(stroke
				(width 0.1)
				(type default)
			)
			(layer "F.Fab")
		)
		(fp_line
			(start 0.299974 0.150114)
			(end -0.299974 0.150114)
			(stroke
				(width 0.1)
				(type default)
			)
			(layer "F.Fab")
		)
		(fp_line
			(start -0.299974 -0.150114)
			(end 0.299974 -0.150114)
			(stroke
				(width 0.1)
				(type default)
			)
			(layer "F.Fab")
		)
		(fp_line
			(start 0.299974 -0.150114)
			(end 0.299974 0.150114)
			(stroke
				(width 0.1)
				(type default)
			)
			(layer "F.Fab")
		)
		(pad "1" smd rect
			(at -0.2667 0 270)
			(size 0.3048 0.381)
			(layers "F.Cu" "F.Mask" "F.Paste")
			(net "P5E_CPU1_P0_TX_C_DN<12>")
		)
		(pad "2" smd rect
			(at 0.2667 0 270)
			(size 0.3048 0.381)
			(layers "F.Cu" "F.Mask" "F.Paste")
			(net "P5E_CPU1_P0_TX_DN<12>")
		)
	)
)
